(kicad_pcb
	(version 20260206)
	(generator "pcbnew")
	(generator_version "10.0")
	(general
		(thickness 1.6)
		(legacy_teardrops no)
	)
	(paper "A4")
	(title_block
		(title "netronome-mezz — pcbd0082-001_rev01_jul9_a.brd")
		(comment 1 "Open CloudServer (Microsoft) / footprints 341-350 of 714")
	)
	(layers
		(0 "F.Cu" signal "TOP")
		(4 "In1.Cu" signal "02_GND")
		(6 "In2.Cu" signal "03_SIG")
		(8 "In3.Cu" signal "04_SIG")
		(10 "In4.Cu" signal "05_GND")
		(12 "In5.Cu" signal "06_PWR1")
		(14 "In6.Cu" signal "07_SIG")
		(16 "In7.Cu" signal "08_SIG")
		(18 "In8.Cu" signal "09_GND")
		(2 "B.Cu" signal "BOTTOM")
		(9 "F.Adhes" user "F.Adhesive")
		(11 "B.Adhes" user "B.Adhesive")
		(13 "F.Paste" user "Package Geometry/Pastemask Top")
		(15 "B.Paste" user "Package Geometry/Pastemask Bottom")
		(5 "F.SilkS" user "Ref Des/Silkscreen Top")
		(7 "B.SilkS" user "Ref Des/Silkscreen Bottom")
		(1 "F.Mask" user "Board Geometry/Soldermask Top")
		(3 "B.Mask" user "Board Geometry/Soldermask Bottom")
		(17 "Dwgs.User" user "User.Drawings")
		(19 "Cmts.User" user "User.Comments")
		(21 "Eco1.User" user "User.Eco1")
		(23 "Eco2.User" user "User.Eco2")
		(25 "Edge.Cuts" user "Board Geometry/Outline")
		(27 "Margin" user)
		(31 "F.CrtYd" user "Package Geometry/Place Bound Top")
		(29 "B.CrtYd" user "Package Geometry/Place Bound Bottom")
		(35 "F.Fab" user "Ref Des/Assembly Top")
		(33 "B.Fab" user "Ref Des/Assembly Bottom")
		(45 "User.4" user "COMPVAL_TYPE_BOTTOM")
	)
	(footprint ""
		(layer "B.Cu")
		(at 45.237019 33.54197)
		(property "Reference" "C79"
			(at 1.472311 -0.64897 270)
			(unlocked yes)
			(layer "B.SilkS")
			(effects
				(font
					(size 0.7874 0.5842)
					(thickness 0.127)
				)
				(justify mirror)
			)
		)
		(property "Value" ""
			(at 0 0 0)
			(layer "B.Fab")
			(effects
				(font
					(size 1.27 1.27)
				)
				(justify mirror)
			)
		)
		(duplicate_pad_numbers_are_jumpers no)
		(fp_circle
			(center 0 0)
			(end 0.104648 0)
			(stroke
				(width 0.1016)
				(type default)
			)
			(fill no)
			(layer "B.SilkS")
		)
		(fp_poly
			(pts
				(xy 0.381 -0.889) (xy 0.381 0.889) (xy -0.381 0.889) (xy -0.381 -0.889)
			)
			(stroke
				(width 0)
				(type default)
			)
			(fill no)
			(layer "B.CrtYd")
		)
		(fp_line
			(start -0.508 -1.016)
			(end -0.508 1.016)
			(stroke
				(width 0.0254)
				(type default)
			)
			(layer "B.Fab")
		)
		(fp_line
			(start -0.508 1.016)
			(end 0.508 1.016)
			(stroke
				(width 0.0254)
				(type default)
			)
			(layer "B.Fab")
		)
		(fp_line
			(start 0.254 -1.016)
			(end -0.508 -1.016)
			(stroke
				(width 0.0254)
				(type default)
			)
			(layer "B.Fab")
		)
		(fp_line
			(start 0.508 -1.016)
			(end 0.254 -1.016)
			(stroke
				(width 0.0254)
				(type default)
			)
			(layer "B.Fab")
		)
		(fp_line
			(start 0.508 1.016)
			(end 0.508 -1.016)
			(stroke
				(width 0.0254)
				(type default)
			)
			(layer "B.Fab")
		)
		(pad "1" smd custom
			(at 0 -0.500126 180)
			(size 0.127 0.127)
			(layers "B.Cu" "B.Mask" "B.Paste")
			(net "VDD_CORE")
			(options
				(clearance outline)
				(anchor circle)
			)
			(primitives
				(gr_poly
					(pts
						(xy -0.1778 0.254) (xy 0.1778 0.254) (xy 0.254 0.1778) (xy 0.254 -0.1778) (xy 0.1778 -0.254) (xy -0.1778 -0.254)
						(xy -0.254 -0.1778) (xy -0.254 0.1778)
					)
					(width 0)
					(fill yes)
				)
			)
		)
		(pad "2" smd custom
			(at 0 0.500126 180)
			(size 0.127 0.127)
			(layers "B.Cu" "B.Mask" "B.Paste")
			(net "GND")
			(options
				(clearance outline)
				(anchor circle)
			)
			(primitives
				(gr_poly
					(pts
						(xy -0.1778 0.254) (xy 0.1778 0.254) (xy 0.254 0.1778) (xy 0.254 -0.1778) (xy 0.1778 -0.254) (xy -0.1778 -0.254)
						(xy -0.254 -0.1778) (xy -0.254 0.1778)
					)
					(width 0)
					(fill yes)
				)
			)
		)
	)
	(footprint ""
		(layer "B.Cu")
		(at 83.450989 18.255996)
		(property "Reference" "V2_A-A11"
			(at 0 0 0)
			(layer "B.SilkS")
			(hide yes)
			(effects
				(font
					(size 1.27 1.27)
				)
				(justify mirror)
			)
		)
		(property "Value" ""
			(at 0 0 0)
			(layer "B.Fab")
			(effects
				(font
					(size 1.27 1.27)
				)
				(justify mirror)
			)
		)
		(duplicate_pad_numbers_are_jumpers no)
		(pad "1" thru_hole circle
			(at 0 0 180)
			(size 0.4572 0.4572)
			(drill 0.20574)
			(layers "*.Cu" "*.Mask")
			(remove_unused_layers no)
			(net "DDR0_32A_A11")
			(clearance 0.1143)
			(thermal_gap 0.1143)
		)
	)
	(footprint ""
		(layer "B.Cu")
		(at 60.736988 14.042009 90)
		(property "Reference" "R145"
			(at 0 0 90)
			(layer "B.SilkS")
			(hide yes)
			(effects
				(font
					(size 1.27 1.27)
				)
				(justify mirror)
			)
		)
		(property "Value" ""
			(at 0 0 90)
			(layer "B.Fab")
			(effects
				(font
					(size 1.27 1.27)
				)
				(justify mirror)
			)
		)
		(duplicate_pad_numbers_are_jumpers no)
		(fp_circle
			(center 0 0)
			(end 0 0.104648)
			(stroke
				(width 0.1016)
				(type default)
			)
			(fill no)
			(layer "B.SilkS")
		)
		(fp_poly
			(pts
				(xy 0.381 -0.889) (xy 0.381 0.889) (xy -0.381 0.889) (xy -0.381 -0.889)
			)
			(stroke
				(width 0)
				(type default)
			)
			(fill no)
			(layer "B.CrtYd")
		)
		(fp_line
			(start 0.508 -1.016)
			(end 0.254 -1.016)
			(stroke
				(width 0.0254)
				(type default)
			)
			(layer "B.Fab")
		)
		(fp_line
			(start 0.254 -1.016)
			(end -0.508 -1.016)
			(stroke
				(width 0.0254)
				(type default)
			)
			(layer "B.Fab")
		)
		(fp_line
			(start -0.508 -1.016)
			(end -0.508 1.016)
			(stroke
				(width 0.0254)
				(type default)
			)
			(layer "B.Fab")
		)
		(fp_line
			(start 0.508 1.016)
			(end 0.508 -1.016)
			(stroke
				(width 0.0254)
				(type default)
			)
			(layer "B.Fab")
		)
		(fp_line
			(start -0.508 1.016)
			(end 0.508 1.016)
			(stroke
				(width 0.0254)
				(type default)
			)
			(layer "B.Fab")
		)
		(pad "1" smd custom
			(at 0 -0.500126 270)
			(size 0.127 0.127)
			(layers "B.Cu" "B.Mask" "B.Paste")
			(net "VDD_CORE")
			(options
				(clearance outline)
				(anchor circle)
			)
			(primitives
				(gr_poly
					(pts
						(xy -0.1778 0.254) (xy 0.1778 0.254) (xy 0.254 0.1778) (xy 0.254 -0.1778) (xy 0.1778 -0.254) (xy -0.1778 -0.254)
						(xy -0.254 -0.1778) (xy -0.254 0.1778)
					)
					(width 0)
					(fill yes)
				)
			)
		)
		(pad "2" smd custom
			(at 0 0.500126 270)
			(size 0.127 0.127)
			(layers "B.Cu" "B.Mask" "B.Paste")
			(net "VDDA_DDR0_32B")
			(options
				(clearance outline)
				(anchor circle)
			)
			(primitives
				(gr_poly
					(pts
						(xy -0.1778 0.254) (xy 0.1778 0.254) (xy 0.254 0.1778) (xy 0.254 -0.1778) (xy 0.1778 -0.254) (xy -0.1778 -0.254)
						(xy -0.254 -0.1778) (xy -0.254 0.1778)
					)
					(width 0)
					(fill yes)
				)
			)
		)
	)
	(footprint ""
		(layer "B.Cu")
		(at 52.737004 7.042023 90)
		(property "Reference" "C101"
			(at 0 0 90)
			(layer "B.SilkS")
			(hide yes)
			(effects
				(font
					(size 1.27 1.27)
				)
				(justify mirror)
			)
		)
		(property "Value" ""
			(at 0 0 90)
			(layer "B.Fab")
			(effects
				(font
					(size 1.27 1.27)
				)
				(justify mirror)
			)
		)
		(duplicate_pad_numbers_are_jumpers no)
		(fp_circle
			(center 0 0)
			(end 0 0.104648)
			(stroke
				(width 0.1016)
				(type default)
			)
			(fill no)
			(layer "B.SilkS")
		)
		(fp_poly
			(pts
				(xy 0.381 -0.889) (xy 0.381 0.889) (xy -0.381 0.889) (xy -0.381 -0.889)
			)
			(stroke
				(width 0)
				(type default)
			)
			(fill no)
			(layer "B.CrtYd")
		)
		(fp_line
			(start 0.508 -1.016)
			(end 0.254 -1.016)
			(stroke
				(width 0.0254)
				(type default)
			)
			(layer "B.Fab")
		)
		(fp_line
			(start 0.254 -1.016)
			(end -0.508 -1.016)
			(stroke
				(width 0.0254)
				(type default)
			)
			(layer "B.Fab")
		)
		(fp_line
			(start -0.508 -1.016)
			(end -0.508 1.016)
			(stroke
				(width 0.0254)
				(type default)
			)
			(layer "B.Fab")
		)
		(fp_line
			(start 0.508 1.016)
			(end 0.508 -1.016)
			(stroke
				(width 0.0254)
				(type default)
			)
			(layer "B.Fab")
		)
		(fp_line
			(start -0.508 1.016)
			(end 0.508 1.016)
			(stroke
				(width 0.0254)
				(type default)
			)
			(layer "B.Fab")
		)
		(pad "1" smd custom
			(at 0 -0.500126 270)
			(size 0.127 0.127)
			(layers "B.Cu" "B.Mask" "B.Paste")
			(net "VDDAH_SERDES")
			(options
				(clearance outline)
				(anchor circle)
			)
			(primitives
				(gr_poly
					(pts
						(xy -0.1778 0.254) (xy 0.1778 0.254) (xy 0.254 0.1778) (xy 0.254 -0.1778) (xy 0.1778 -0.254) (xy -0.1778 -0.254)
						(xy -0.254 -0.1778) (xy -0.254 0.1778)
					)
					(width 0)
					(fill yes)
				)
			)
		)
		(pad "2" smd custom
			(at 0 0.500126 270)
			(size 0.127 0.127)
			(layers "B.Cu" "B.Mask" "B.Paste")
			(net "GND")
			(options
				(clearance outline)
				(anchor circle)
			)
			(primitives
				(gr_poly
					(pts
						(xy -0.1778 0.254) (xy 0.1778 0.254) (xy 0.254 0.1778) (xy 0.254 -0.1778) (xy 0.1778 -0.254) (xy -0.1778 -0.254)
						(xy -0.254 -0.1778) (xy -0.254 0.1778)
					)
					(width 0)
					(fill yes)
				)
			)
		)
	)
	(footprint ""
		(layer "B.Cu")
		(at 3.3655 16.129 90)
		(property "Reference" "R385"
			(at 0 0 90)
			(layer "B.SilkS")
			(hide yes)
			(effects
				(font
					(size 1.27 1.27)
				)
				(justify mirror)
			)
		)
		(property "Value" "0"
			(at 0.148158 1.3462 0)
			(unlocked yes)
			(layer "B.Fab")
			(hide yes)
			(effects
				(font
					(size 1.27 0.9652)
					(thickness 0.000001)
				)
				(justify left mirror)
			)
		)
		(property "Device Type" "REST1111"
			(at 0.148158 1.3462 0)
			(unlocked yes)
			(layer "B.Fab")
			(hide yes)
			(effects
				(font
					(size 1.27 0.9652)
					(thickness 0.000001)
				)
				(justify left mirror)
			)
		)
		(duplicate_pad_numbers_are_jumpers no)
		(fp_poly
			(pts
				(xy -0.635 1.0668) (xy -0.635 -1.0668) (xy 0.635 -1.0668) (xy 0.635 1.0668)
			)
			(stroke
				(width 0)
				(type default)
			)
			(fill no)
			(layer "B.CrtYd")
		)
		(fp_line
			(start 0.254 -0.508)
			(end -0.254 -0.508)
			(stroke
				(width 0.0254)
				(type default)
			)
			(layer "B.Fab")
		)
		(fp_line
			(start -0.254 -0.508)
			(end -0.254 0.508)
			(stroke
				(width 0.0254)
				(type default)
			)
			(layer "B.Fab")
		)
		(fp_line
			(start 0.254 0.508)
			(end 0.254 -0.508)
			(stroke
				(width 0.0254)
				(type default)
			)
			(layer "B.Fab")
		)
		(fp_line
			(start -0.254 0.508)
			(end 0.254 0.508)
			(stroke
				(width 0.0254)
				(type default)
			)
			(layer "B.Fab")
		)
		(pad "1" smd rect
			(at 0 -0.4191 270)
			(size 0.508 0.5334)
			(layers "B.Cu" "B.Mask" "B.Paste")
			(net "NWK0_I2C_SCL")
		)
		(pad "2" smd rect
			(at 0 0.4191 270)
			(size 0.508 0.5334)
			(layers "B.Cu" "B.Mask" "B.Paste")
			(net "MUX_NFP_GPIO0_NWK0_I2C_SCL")
		)
		(zone
			(layer "B.Cu")
			(hatch none 0.5)
			(connect_pads
				(clearance 0)
			)
			(min_thickness 0.25)
			(keepout
				(tracks not_allowed)
				(vias allowed)
				(pads allowed)
				(copperpour not_allowed)
				(footprints allowed)
			)
			(placement
				(enabled no)
				(sheetname "")
			)
			(fill
				(thermal_gap 0.5)
				(thermal_bridge_width 0.5)
				(island_removal_mode 0)
			)
			(polygon
				(pts
					(xy 3.3401 16.1544) (xy 3.3909 16.1544) (xy 3.3909 16.1036) (xy 3.3401 16.1036)
				)
			)
		)
	)
	(footprint ""
		(layer "B.Cu")
		(at 3.683 17.4498)
		(property "Reference" "R394"
			(at 0.86233 3.8862 270)
			(unlocked yes)
			(layer "B.SilkS")
			(effects
				(font
					(size 0.7874 0.5842)
					(thickness 0.127)
				)
				(justify left mirror)
			)
		)
		(property "Value" "240"
			(at 0.148158 1.3462 270)
			(unlocked yes)
			(layer "B.Fab")
			(hide yes)
			(effects
				(font
					(size 1.27 0.9652)
					(thickness 0.000001)
				)
				(justify left mirror)
			)
		)
		(property "Device Type" "REST0009"
			(at 0.148158 1.3462 270)
			(unlocked yes)
			(layer "B.Fab")
			(hide yes)
			(effects
				(font
					(size 1.27 0.9652)
					(thickness 0.000001)
				)
				(justify left mirror)
			)
		)
		(duplicate_pad_numbers_are_jumpers no)
		(fp_poly
			(pts
				(xy -0.635 1.0668) (xy -0.635 -1.0668) (xy 0.635 -1.0668) (xy 0.635 1.0668)
			)
			(stroke
				(width 0)
				(type default)
			)
			(fill no)
			(layer "B.CrtYd")
		)
		(fp_line
			(start -0.254 -0.508)
			(end -0.254 0.508)
			(stroke
				(width 0.0254)
				(type default)
			)
			(layer "B.Fab")
		)
		(fp_line
			(start -0.254 0.508)
			(end 0.254 0.508)
			(stroke
				(width 0.0254)
				(type default)
			)
			(layer "B.Fab")
		)
		(fp_line
			(start 0.254 -0.508)
			(end -0.254 -0.508)
			(stroke
				(width 0.0254)
				(type default)
			)
			(layer "B.Fab")
		)
		(fp_line
			(start 0.254 0.508)
			(end 0.254 -0.508)
			(stroke
				(width 0.0254)
				(type default)
			)
			(layer "B.Fab")
		)
		(pad "1" smd rect
			(at 0 -0.4191 180)
			(size 0.508 0.5334)
			(layers "B.Cu" "B.Mask" "B.Paste")
			(net "13N4351")
		)
		(pad "2" smd rect
			(at 0 0.4191 180)
			(size 0.508 0.5334)
			(layers "B.Cu" "B.Mask" "B.Paste")
			(net "VDD_3.3V")
		)
		(zone
			(layer "B.Cu")
			(hatch none 0.5)
			(connect_pads
				(clearance 0)
			)
			(min_thickness 0.25)
			(keepout
				(tracks not_allowed)
				(vias allowed)
				(pads allowed)
				(copperpour not_allowed)
				(footprints allowed)
			)
			(placement
				(enabled no)
				(sheetname "")
			)
			(fill
				(thermal_gap 0.5)
				(thermal_bridge_width 0.5)
				(island_removal_mode 0)
			)
			(polygon
				(pts
					(xy 3.6576 17.4244) (xy 3.6576 17.4752) (xy 3.7084 17.4752) (xy 3.7084 17.4244)
				)
			)
		)
	)
	(footprint ""
		(layer "B.Cu")
		(at 53.467 0.762 180)
		(property "Reference" "C147"
			(at 0.145212 0.8763 270)
			(unlocked yes)
			(layer "B.SilkS")
			(effects
				(font
					(size 0.7874 0.5842)
					(thickness 0.127)
				)
				(justify left mirror)
			)
		)
		(property "Value" "0.22UF"
			(at 0.091846 0.2921 90)
			(unlocked yes)
			(layer "B.Fab")
			(hide yes)
			(effects
				(font
					(size 0.7874 0.5842)
					(thickness 0.2032)
				)
				(justify left mirror)
			)
		)
		(property "Device Type" "CAPC0062"
			(at 0.091846 0.2921 90)
			(unlocked yes)
			(layer "B.Fab")
			(hide yes)
			(effects
				(font
					(size 0.7874 0.5842)
					(thickness 0.2032)
				)
				(justify left mirror)
			)
		)
		(duplicate_pad_numbers_are_jumpers no)
		(fp_poly
			(pts
				(xy -0.635 1.0668) (xy -0.635 -1.0668) (xy 0.635 -1.0668) (xy 0.635 1.0668)
			)
			(stroke
				(width 0)
				(type default)
			)
			(fill no)
			(layer "B.CrtYd")
		)
		(fp_line
			(start 0.254 0.508)
			(end 0.254 -0.508)
			(stroke
				(width 0.0254)
				(type default)
			)
			(layer "B.Fab")
		)
		(fp_line
			(start 0.254 -0.508)
			(end -0.254 -0.508)
			(stroke
				(width 0.0254)
				(type default)
			)
			(layer "B.Fab")
		)
		(fp_line
			(start -0.254 0.508)
			(end 0.254 0.508)
			(stroke
				(width 0.0254)
				(type default)
			)
			(layer "B.Fab")
		)
		(fp_line
			(start -0.254 -0.508)
			(end -0.254 0.508)
			(stroke
				(width 0.0254)
				(type default)
			)
			(layer "B.Fab")
		)
		(pad "1" smd rect
			(at 0 -0.4191)
			(size 0.508 0.5334)
			(layers "B.Cu" "B.Mask" "B.Paste")
			(net "_NFP_PCIE0_PER5_P")
		)
		(pad "2" smd rect
			(at 0 0.4191)
			(size 0.508 0.5334)
			(layers "B.Cu" "B.Mask" "B.Paste")
			(net "NFP_PCIE0_PER5_P")
		)
		(zone
			(layer "B.Cu")
			(hatch none 0.5)
			(connect_pads
				(clearance 0)
			)
			(min_thickness 0.25)
			(keepout
				(tracks not_allowed)
				(vias allowed)
				(pads allowed)
				(copperpour not_allowed)
				(footprints allowed)
			)
			(placement
				(enabled no)
				(sheetname "")
			)
			(fill
				(thermal_gap 0.5)
				(thermal_bridge_width 0.5)
				(island_removal_mode 0)
			)
			(polygon
				(pts
					(xy 53.4924 0.7874) (xy 53.4924 0.7366) (xy 53.4416 0.7366) (xy 53.4416 0.7874)
				)
			)
		)
	)
	(footprint ""
		(layer "B.Cu")
		(at 54.229 45.593)
		(property "Reference" "TP40"
			(at -0.15367 4.064 270)
			(unlocked yes)
			(layer "B.SilkS")
			(effects
				(font
					(size 0.7874 0.5842)
					(thickness 0.127)
				)
				(justify left mirror)
			)
		)
		(property "Value" "*"
			(at 0.4826 -0.14732 0)
			(unlocked yes)
			(layer "B.Fab")
			(hide yes)
			(effects
				(font
					(size 1.27 0.9652)
					(thickness 0.000001)
				)
				(justify left mirror)
			)
		)
		(property "Device Type" "TP_SMALL"
			(at 0.4826 -0.14732 0)
			(unlocked yes)
			(layer "B.Fab")
			(hide yes)
			(effects
				(font
					(size 1.27 0.9652)
					(thickness 0.000001)
				)
				(justify left mirror)
			)
		)
		(duplicate_pad_numbers_are_jumpers no)
		(fp_line
			(start -0.8636 -0.8636)
			(end 0.8636 -0.8636)
			(stroke
				(width 0.1524)
				(type default)
			)
			(layer "B.SilkS")
		)
		(fp_line
			(start -0.8636 0.8636)
			(end -0.8636 -0.8636)
			(stroke
				(width 0.1524)
				(type default)
			)
			(layer "B.SilkS")
		)
		(fp_line
			(start 0.8636 -0.8636)
			(end 0.8636 0.8636)
			(stroke
				(width 0.1524)
				(type default)
			)
			(layer "B.SilkS")
		)
		(fp_line
			(start 0.8636 0.8636)
			(end -0.8636 0.8636)
			(stroke
				(width 0.1524)
				(type default)
			)
			(layer "B.SilkS")
		)
		(fp_poly
			(pts
				(xy 0.635 -0.635) (xy 0.635 0.635) (xy -0.635 0.635) (xy -0.635 -0.635)
			)
			(stroke
				(width 0)
				(type default)
			)
			(fill no)
			(layer "B.CrtYd")
		)
		(pad "1" smd rect
			(at 0 0 180)
			(size 1.27 1.27)
			(layers "B.Cu" "B.Mask" "B.Paste")
			(net "GND")
		)
	)
	(footprint ""
		(layer "B.Cu")
		(at 81.050994 25.813004)
		(property "Reference" "V3_A-BA2"
			(at 0 0 0)
			(layer "B.SilkS")
			(hide yes)
			(effects
				(font
					(size 1.27 1.27)
				)
				(justify mirror)
			)
		)
		(property "Value" ""
			(at 0 0 0)
			(layer "B.Fab")
			(effects
				(font
					(size 1.27 1.27)
				)
				(justify mirror)
			)
		)
		(duplicate_pad_numbers_are_jumpers no)
		(pad "1" thru_hole circle
			(at 0 0 180)
			(size 0.4572 0.4572)
			(drill 0.20574)
			(layers "*.Cu" "*.Mask")
			(remove_unused_layers no)
			(net "DDR0_32A_BA2")
			(clearance 0.1143)
			(thermal_gap 0.1143)
		)
	)
	(footprint ""
		(layer "B.Cu")
		(at 0.6604 9.8552 180)
		(property "Reference" "R374"
			(at 0.4064 0.30353 0)
			(unlocked yes)
			(layer "B.SilkS")
			(effects
				(font
					(size 0.7874 0.5842)
					(thickness 0.127)
				)
				(justify left mirror)
			)
		)
		(property "Value" "4.75K"
			(at 0.148158 1.3462 90)
			(unlocked yes)
			(layer "B.Fab")
			(hide yes)
			(effects
				(font
					(size 1.27 0.9652)
					(thickness 0.000001)
				)
				(justify left mirror)
			)
		)
		(property "Device Type" "REST4024"
			(at 0.148158 1.3462 90)
			(unlocked yes)
			(layer "B.Fab")
			(hide yes)
			(effects
				(font
					(size 1.27 0.9652)
					(thickness 0.000001)
				)
				(justify left mirror)
			)
		)
		(duplicate_pad_numbers_are_jumpers no)
		(fp_poly
			(pts
				(xy -0.635 1.0668) (xy -0.635 -1.0668) (xy 0.635 -1.0668) (xy 0.635 1.0668)
			)
			(stroke
				(width 0)
				(type default)
			)
			(fill no)
			(layer "B.CrtYd")
		)
		(fp_line
			(start 0.254 0.508)
			(end 0.254 -0.508)
			(stroke
				(width 0.0254)
				(type default)
			)
			(layer "B.Fab")
		)
		(fp_line
			(start 0.254 -0.508)
			(end -0.254 -0.508)
			(stroke
				(width 0.0254)
				(type default)
			)
			(layer "B.Fab")
		)
		(fp_line
			(start -0.254 0.508)
			(end 0.254 0.508)
			(stroke
				(width 0.0254)
				(type default)
			)
			(layer "B.Fab")
		)
		(fp_line
			(start -0.254 -0.508)
			(end -0.254 0.508)
			(stroke
				(width 0.0254)
				(type default)
			)
			(layer "B.Fab")
		)
		(pad "1" smd rect
			(at 0 -0.4191)
			(size 0.508 0.5334)
			(layers "B.Cu" "B.Mask" "B.Paste")
			(net "NWK1_I2C_SCL")
		)
		(pad "2" smd rect
			(at 0 0.4191)
			(size 0.508 0.5334)
			(layers "B.Cu" "B.Mask" "B.Paste")
			(net "EXT_3.3V")
		)
		(zone
			(layer "B.Cu")
			(hatch none 0.5)
			(connect_pads
				(clearance 0)
			)
			(min_thickness 0.25)
			(keepout
				(tracks not_allowed)
				(vias allowed)
				(pads allowed)
				(copperpour not_allowed)
				(footprints allowed)
			)
			(placement
				(enabled no)
				(sheetname "")
			)
			(fill
				(thermal_gap 0.5)
				(thermal_bridge_width 0.5)
				(island_removal_mode 0)
			)
			(polygon
				(pts
					(xy 0.6858 9.8806) (xy 0.6858 9.8298) (xy 0.635 9.8298) (xy 0.635 9.8806)
				)
			)
		)
	)
)
